# BASEBOARD_FAB2 (Tioga Pass) — schematic netlist excerpt (pin names and nets, part order shuffled) for the footprints in the layout excerpt that follows; sources: Cadence DE-HDL packaged netlist, KiCad conversion of Wiwynn_Tioga_Pass_MB.brd

C1L119  CAP  1.0UF 16V 10% X6S  pkg 0402  page 189 : A = P3V3_STBY ; B = GND
C9T5  CAPP  470UF 2.5V 20% ALUM  pkg 3018  page 225 : A = PVDDQ_GHJ ; B = GND
C7M1  CAP_A  47UF 4V 20% X5R  pkg 0603V  page 228 : A = PVDDQ_KLM ; B = GND

(kicad_pcb
	(version 20260206)
	(generator "pcbnew")
	(generator_version "10.0")
	(general
		(thickness 1.6)
		(legacy_teardrops no)
	)
	(paper "A4")
	(title_block
		(title "Wiwynn_Tioga_Pass_MB.brd")
		(comment 1 "Tioga Pass / footprints 3831-3833 of 4770")
	)
	(layers
		(0 "F.Cu" signal "TOP")
		(4 "In1.Cu" signal "L2GND")
		(6 "In2.Cu" signal "L3")
		(8 "In3.Cu" signal "L4GND")
		(10 "In4.Cu" signal "L5")
		(12 "In5.Cu" signal "L6GND")
		(14 "In6.Cu" signal "L7VCC")
		(16 "In7.Cu" signal "L8VCC")
		(18 "In8.Cu" signal "L9GND")
		(20 "In9.Cu" signal "L10")
		(22 "In10.Cu" signal "L11GND")
		(24 "In11.Cu" signal "L12")
		(26 "In12.Cu" signal "L13GND")
		(2 "B.Cu" signal "BOTTOM")
		(9 "F.Adhes" user "F.Adhesive")
		(11 "B.Adhes" user "B.Adhesive")
		(13 "F.Paste" user "Package Geometry/Pastemask Top")
		(15 "B.Paste" user "Package Geometry/Pastemask Bottom")
		(5 "F.SilkS" user "Ref Des/Silkscreen Top")
		(7 "B.SilkS" user "Ref Des/Silkscreen Bottom")
		(1 "F.Mask" user "Board Geometry/Soldermask Top")
		(3 "B.Mask" user "Board Geometry/Soldermask Bottom")
		(17 "Dwgs.User" user "User.Drawings")
		(19 "Cmts.User" user "User.Comments")
		(21 "Eco1.User" user "User.Eco1")
		(23 "Eco2.User" user "User.Eco2")
		(25 "Edge.Cuts" user "Board Geometry/Outline")
		(27 "Margin" user)
		(31 "F.CrtYd" user "Package Geometry/Place Bound Top")
		(29 "B.CrtYd" user "Package Geometry/Place Bound Bottom")
		(35 "F.Fab" user "Ref Des/Assembly Top")
		(33 "B.Fab" user "Ref Des/Assembly Bottom")
	)
	(footprint ""
		(layer "B.Cu")
		(at 17.9832 -19.6342 -90)
		(property "Reference" "C9T5"
			(at -3.02133 8.255 0)
			(unlocked yes)
			(layer "B.SilkS")
			(effects
				(font
					(size 0.7874 0.5842)
					(thickness 0.1524)
				)
				(justify mirror)
			)
		)
		(property "Value" ""
			(at 0 0 90)
			(layer "B.Fab")
			(effects
				(font
					(size 1.27 1.27)
				)
				(justify mirror)
			)
		)
		(duplicate_pad_numbers_are_jumpers no)
		(fp_line
			(start -2.286 7.366)
			(end -1.600708 7.366)
			(stroke
				(width 0.1524)
				(type default)
			)
			(layer "B.SilkS")
		)
		(fp_line
			(start -2.286 7.366)
			(end -2.286 1.63195)
			(stroke
				(width 0.1524)
				(type default)
			)
			(layer "B.SilkS")
		)
		(fp_line
			(start 2.286 7.366)
			(end 1.60147 7.366)
			(stroke
				(width 0.1524)
				(type default)
			)
			(layer "B.SilkS")
		)
		(fp_line
			(start 2.286 7.366)
			(end 2.286 1.632712)
			(stroke
				(width 0.1524)
				(type default)
			)
			(layer "B.SilkS")
		)
		(fp_line
			(start -2.504948 1.633728)
			(end -1.6002 1.633728)
			(stroke
				(width 0.1524)
				(type default)
			)
			(layer "B.SilkS")
		)
		(fp_line
			(start 2.563114 1.633728)
			(end 1.6002 1.633728)
			(stroke
				(width 0.1524)
				(type default)
			)
			(layer "B.SilkS")
		)
		(fp_line
			(start -2.504948 -1.616456)
			(end -2.504948 1.633728)
			(stroke
				(width 0.1524)
				(type default)
			)
			(layer "B.SilkS")
		)
		(fp_line
			(start -1.6002 -1.616456)
			(end -2.504948 -1.616456)
			(stroke
				(width 0.1524)
				(type default)
			)
			(layer "B.SilkS")
		)
		(fp_line
			(start 1.6002 -1.616456)
			(end 2.563114 -1.616456)
			(stroke
				(width 0.1524)
				(type default)
			)
			(layer "B.SilkS")
		)
		(fp_line
			(start 2.563114 -1.616456)
			(end 2.563114 1.633728)
			(stroke
				(width 0.1524)
				(type default)
			)
			(layer "B.SilkS")
		)
		(fp_rect
			(start 2.286 -0.254)
			(end -2.286 7.366)
			(stroke
				(width 0)
				(type default)
			)
			(fill no)
			(layer "B.CrtYd")
		)
		(fp_line
			(start -2.286 7.366)
			(end 2.286 7.366)
			(stroke
				(width 0.1)
				(type default)
			)
			(layer "B.Fab")
		)
		(fp_line
			(start 2.286 7.366)
			(end 2.286 -0.254)
			(stroke
				(width 0.1)
				(type default)
			)
			(layer "B.Fab")
		)
		(fp_line
			(start -2.286 -0.254)
			(end -2.286 7.366)
			(stroke
				(width 0.1)
				(type default)
			)
			(layer "B.Fab")
		)
		(fp_line
			(start 2.286 -0.254)
			(end -2.286 -0.254)
			(stroke
				(width 0.1)
				(type default)
			)
			(layer "B.Fab")
		)
		(pad "1" smd rect
			(at 0 0 90)
			(size 2.54 3.048)
			(layers "B.Cu" "B.Mask" "B.Paste")
			(net "PVDDQ_GHJ")
		)
		(pad "2" smd rect
			(at 0 7.112 90)
			(size 2.54 3.048)
			(layers "B.Cu" "B.Mask" "B.Paste")
			(net "GND")
		)
	)
	(footprint ""
		(layer "B.Cu")
		(at 404.483062 -1.524508)
		(property "Reference" "C1L119"
			(at 0.8382 -0.67818 0)
			(unlocked yes)
			(layer "B.SilkS")
			(effects
				(font
					(size 0.4064 0.254)
					(thickness 0.1524)
				)
				(justify left mirror)
			)
		)
		(property "Value" ""
			(at 0 0 0)
			(layer "B.Fab")
			(effects
				(font
					(size 1.27 1.27)
				)
				(justify mirror)
			)
		)
		(duplicate_pad_numbers_are_jumpers no)
		(fp_poly
			(pts
				(xy -0.3048 -0.1016) (xy -0.3048 0.9906) (xy 0.3048 0.9906) (xy 0.3048 -0.1016)
			)
			(stroke
				(width 0)
				(type default)
			)
			(fill no)
			(layer "B.CrtYd")
		)
		(fp_line
			(start -0.3048 -0.1016)
			(end 0.3048 -0.1016)
			(stroke
				(width 0.1)
				(type default)
			)
			(layer "B.Fab")
		)
		(fp_line
			(start -0.3048 0.9906)
			(end -0.3048 -0.1016)
			(stroke
				(width 0.1)
				(type default)
			)
			(layer "B.Fab")
		)
		(fp_line
			(start 0.3048 -0.1016)
			(end 0.3048 0.9906)
			(stroke
				(width 0.1)
				(type default)
			)
			(layer "B.Fab")
		)
		(fp_line
			(start 0.3048 0.9906)
			(end -0.3048 0.9906)
			(stroke
				(width 0.1)
				(type default)
			)
			(layer "B.Fab")
		)
		(pad "1" smd rect
			(at 0 0 180)
			(size 0.508 0.508)
			(layers "B.Cu" "B.Mask" "B.Paste")
			(net "P3V3_STBY")
		)
		(pad "2" smd rect
			(at 0 0.889 180)
			(size 0.508 0.508)
			(layers "B.Cu" "B.Mask" "B.Paste")
			(net "GND")
		)
		(zone
			(layer "B.Cu")
			(hatch none 0.5)
			(connect_pads
				(clearance 0)
			)
			(min_thickness 0.25)
			(keepout
				(tracks allowed)
				(vias not_allowed)
				(pads allowed)
				(copperpour not_allowed)
				(footprints allowed)
			)
			(placement
				(enabled no)
				(sheetname "")
			)
			(fill
				(thermal_gap 0.5)
				(thermal_bridge_width 0.5)
				(island_removal_mode 0)
			)
			(polygon
				(pts
					(xy 404.737062 -1.270508) (xy 404.229062 -1.270508) (xy 404.229062 -0.889508) (xy 404.737062 -0.889508)
				)
			)
		)
		(zone
			(layer "B.Cu")
			(hatch none 0.5)
			(connect_pads
				(clearance 0)
			)
			(min_thickness 0.25)
			(keepout
				(tracks not_allowed)
				(vias allowed)
				(pads allowed)
				(copperpour not_allowed)
				(footprints allowed)
			)
			(placement
				(enabled no)
				(sheetname "")
			)
			(fill
				(thermal_gap 0.5)
				(thermal_bridge_width 0.5)
				(island_removal_mode 0)
			)
			(polygon
				(pts
					(xy 404.737062 -0.889508) (xy 404.229062 -0.889508) (xy 404.229062 -1.270508) (xy 404.737062 -1.270508)
				)
			)
		)
	)
	(footprint ""
		(layer "B.Cu")
		(at 111.381032 -135.4074 90)
		(property "Reference" "C7M1"
			(at -1.848866 0.752348 90)
			(unlocked yes)
			(layer "B.SilkS")
			(effects
				(font
					(size 1.27 0.9652)
					(thickness 0.1524)
				)
				(justify mirror)
			)
		)
		(property "Value" ""
			(at 0 0 90)
			(layer "B.Fab")
			(effects
				(font
					(size 1.27 1.27)
				)
				(justify mirror)
			)
		)
		(duplicate_pad_numbers_are_jumpers no)
		(fp_rect
			(start 0.500126 1.598422)
			(end -0.500126 -0.201422)
			(stroke
				(width 0)
				(type default)
			)
			(fill no)
			(layer "B.CrtYd")
		)
		(fp_line
			(start 0.500126 -0.201422)
			(end -0.500126 -0.201422)
			(stroke
				(width 0.1)
				(type default)
			)
			(layer "B.Fab")
		)
		(fp_line
			(start -0.500126 -0.201422)
			(end -0.500126 1.598422)
			(stroke
				(width 0.1)
				(type default)
			)
			(layer "B.Fab")
		)
		(fp_line
			(start 0.500126 1.598422)
			(end 0.500126 -0.201422)
			(stroke
				(width 0.1)
				(type default)
			)
			(layer "B.Fab")
		)
		(fp_line
			(start -0.500126 1.598422)
			(end 0.500126 1.598422)
			(stroke
				(width 0.1)
				(type default)
			)
			(layer "B.Fab")
		)
		(pad "1" smd rect
			(at 0 0)
			(size 0.889 0.9906)
			(layers "B.Cu" "B.Mask" "B.Paste")
			(net "PVDDQ_KLM")
		)
		(pad "2" smd rect
			(at 0 1.397)
			(size 0.889 0.9906)
			(layers "B.Cu" "B.Mask" "B.Paste")
			(net "GND")
		)
		(zone
			(layer "B.Cu")
			(hatch none 0.5)
			(connect_pads
				(clearance 0)
			)
			(min_thickness 0.25)
			(keepout
				(tracks allowed)
				(vias not_allowed)
				(pads allowed)
				(copperpour not_allowed)
				(footprints allowed)
			)
			(placement
				(enabled no)
				(sheetname "")
			)
			(fill
				(thermal_gap 0.5)
				(thermal_bridge_width 0.5)
				(island_removal_mode 0)
			)
			(polygon
				(pts
					(xy 112.333532 -135.9027) (xy 111.825532 -135.9027) (xy 111.825532 -134.9121) (xy 112.333532 -134.9121)
				)
			)
		)
		(zone
			(layer "B.Cu")
			(hatch none 0.5)
			(connect_pads
				(clearance 0)
			)
			(min_thickness 0.25)
			(keepout
				(tracks not_allowed)
				(vias allowed)
				(pads allowed)
				(copperpour not_allowed)
				(footprints allowed)
			)
			(placement
				(enabled no)
				(sheetname "")
			)
			(fill
				(thermal_gap 0.5)
				(thermal_bridge_width 0.5)
				(island_removal_mode 0)
			)
			(polygon
				(pts
					(xy 112.333532 -135.9027) (xy 111.825532 -135.9027) (xy 111.825532 -134.9121) (xy 112.333532 -134.9121)
				)
			)
		)
	)
)
